# T6G (Grand Teton) — schematic netlist excerpt (pin names and nets, part order shuffled) for the footprints in the layout excerpt that follows; sources: Cadence DE-HDL packaged netlist, KiCad conversion of 04192023_DAF0TMB3IC0_F0TG_MB_C_brd_V02_OCP.brd

C912  Q_CAP_DIFFBUS  DIFF BUS_0.22UF 6.3V 20% X6S  pkg C0201  page 63 : \1\ = P5E_CPU0_P0_TX_C_DN<10> ; \2\ = P5E_CPU0_P0_TX_DN<10>
C2266  Q_CAP  22UF 4V 20% X6S  pkg C0402  page 72 : A = PVDD11_S3_P1 ; B = GND
H126  HOLE  EMPTY  pkg TH  page 230 : \1\ = NC

(kicad_pcb
	(version 20260206)
	(generator "pcbnew")
	(generator_version "10.0")
	(general
		(thickness 1.6)
		(legacy_teardrops no)
	)
	(paper "A4")
	(title_block
		(title "04192023_DAF0TMB3IC0_F0TG_MB_C_brd_V02_OCP.brd")
		(comment 1 "Grand Teton / footprints 2382-2384 of 8354")
	)
	(layers
		(0 "F.Cu" signal "TOP")
		(4 "In1.Cu" signal "GND")
		(6 "In2.Cu" signal "IN1")
		(8 "In3.Cu" signal "GND1")
		(10 "In4.Cu" signal "IN2")
		(12 "In5.Cu" signal "GND2")
		(14 "In6.Cu" signal "IN3")
		(16 "In7.Cu" signal "GND3")
		(18 "In8.Cu" signal "VCC")
		(20 "In9.Cu" signal "VCC1")
		(22 "In10.Cu" signal "GND4")
		(24 "In11.Cu" signal "IN4")
		(26 "In12.Cu" signal "GND5")
		(28 "In13.Cu" signal "IN5")
		(30 "In14.Cu" signal "GND6")
		(32 "In15.Cu" signal "IN6")
		(34 "In16.Cu" signal "GND7")
		(2 "B.Cu" signal "BOTTOM")
		(9 "F.Adhes" user "F.Adhesive")
		(11 "B.Adhes" user "B.Adhesive")
		(13 "F.Paste" user "Package Geometry/Pastemask Top")
		(15 "B.Paste" user "Package Geometry/Pastemask Bottom")
		(5 "F.SilkS" user "Ref Des/Silkscreen Top")
		(7 "B.SilkS" user "Ref Des/Silkscreen Bottom")
		(1 "F.Mask" user "Board Geometry/Soldermask Top")
		(3 "B.Mask" user "Board Geometry/Soldermask Bottom")
		(17 "Dwgs.User" user "User.Drawings")
		(19 "Cmts.User" user "User.Comments")
		(21 "Eco1.User" user "User.Eco1")
		(23 "Eco2.User" user "User.Eco2")
		(25 "Edge.Cuts" user "Board Geometry/Outline")
		(27 "Margin" user)
		(31 "F.CrtYd" user "Package Geometry/Place Bound Top")
		(29 "B.CrtYd" user "Package Geometry/Place Bound Bottom")
		(35 "F.Fab" user "Ref Des/Assembly Top")
		(33 "B.Fab" user "Ref Des/Assembly Bottom")
	)
	(footprint ""
		(layer "F.Cu")
		(at 110.856014 -259.845302)
		(property "Reference" "C2266"
			(at 0 0 0)
			(layer "F.SilkS")
			(hide yes)
			(effects
				(font
					(size 1.27 1.27)
				)
			)
		)
		(property "Value" ""
			(at 0 0 0)
			(layer "F.Fab")
			(effects
				(font
					(size 1.27 1.27)
				)
			)
		)
		(duplicate_pad_numbers_are_jumpers no)
		(fp_line
			(start -0.7874 -0.4064)
			(end 0.7874 -0.4064)
			(stroke
				(width 0.1524)
				(type default)
			)
			(layer "F.SilkS")
		)
		(fp_line
			(start -0.7874 0.4064)
			(end -0.7874 -0.4064)
			(stroke
				(width 0.1524)
				(type default)
			)
			(layer "F.SilkS")
		)
		(fp_line
			(start 0.7874 -0.4064)
			(end 0.7874 0.4064)
			(stroke
				(width 0.1524)
				(type default)
			)
			(layer "F.SilkS")
		)
		(fp_line
			(start 0.7874 0.4064)
			(end -0.7874 0.4064)
			(stroke
				(width 0.1524)
				(type default)
			)
			(layer "F.SilkS")
		)
		(fp_line
			(start -0.67945 -0.305054)
			(end -0.12065 -0.305054)
			(stroke
				(width 0.1)
				(type default)
			)
			(layer "F.Fab")
		)
		(fp_line
			(start -0.67945 0.3048)
			(end -0.67945 -0.305054)
			(stroke
				(width 0.1)
				(type default)
			)
			(layer "F.Fab")
		)
		(fp_line
			(start -0.12065 -0.305054)
			(end -0.12065 -0.2794)
			(stroke
				(width 0.1)
				(type default)
			)
			(layer "F.Fab")
		)
		(fp_line
			(start -0.12065 -0.2794)
			(end 0.12065 -0.2794)
			(stroke
				(width 0.1)
				(type default)
			)
			(layer "F.Fab")
		)
		(fp_line
			(start -0.12065 0.2794)
			(end -0.12065 0.3048)
			(stroke
				(width 0.1)
				(type default)
			)
			(layer "F.Fab")
		)
		(fp_line
			(start -0.12065 0.3048)
			(end -0.67945 0.3048)
			(stroke
				(width 0.1)
				(type default)
			)
			(layer "F.Fab")
		)
		(fp_line
			(start 0.120396 0.2794)
			(end -0.12065 0.2794)
			(stroke
				(width 0.1)
				(type default)
			)
			(layer "F.Fab")
		)
		(fp_line
			(start 0.120396 0.3048)
			(end 0.120396 0.2794)
			(stroke
				(width 0.1)
				(type default)
			)
			(layer "F.Fab")
		)
		(fp_line
			(start 0.12065 -0.3048)
			(end 0.67945 -0.3048)
			(stroke
				(width 0.1)
				(type default)
			)
			(layer "F.Fab")
		)
		(fp_line
			(start 0.12065 -0.2794)
			(end 0.12065 -0.3048)
			(stroke
				(width 0.1)
				(type default)
			)
			(layer "F.Fab")
		)
		(fp_line
			(start 0.67945 -0.3048)
			(end 0.67945 0.3048)
			(stroke
				(width 0.1)
				(type default)
			)
			(layer "F.Fab")
		)
		(fp_line
			(start 0.67945 0.3048)
			(end 0.120396 0.3048)
			(stroke
				(width 0.1)
				(type default)
			)
			(layer "F.Fab")
		)
		(pad "1" smd circle
			(at -0.40005 0)
			(size 0 0)
			(layers "F.Cu" "F.Mask" "F.Paste")
			(net "PVDD11_S3_P1")
		)
		(pad "2" smd circle
			(at 0.40005 0)
			(size 0 0)
			(layers "F.Cu" "F.Mask" "F.Paste")
			(net "GND")
		)
	)
	(footprint ""
		(layer "F.Cu")
		(at 318.623696 -383.88163 -90)
		(property "Reference" "C912"
			(at 0 0 270)
			(layer "F.SilkS")
			(hide yes)
			(effects
				(font
					(size 1.27 1.27)
				)
			)
		)
		(property "Value" ""
			(at 0 0 270)
			(layer "F.Fab")
			(effects
				(font
					(size 1.27 1.27)
				)
			)
		)
		(duplicate_pad_numbers_are_jumpers no)
		(fp_line
			(start -0.299974 0.150114)
			(end -0.299974 -0.150114)
			(stroke
				(width 0.1)
				(type default)
			)
			(layer "F.Fab")
		)
		(fp_line
			(start 0.299974 0.150114)
			(end -0.299974 0.150114)
			(stroke
				(width 0.1)
				(type default)
			)
			(layer "F.Fab")
		)
		(fp_line
			(start -0.299974 -0.150114)
			(end 0.299974 -0.150114)
			(stroke
				(width 0.1)
				(type default)
			)
			(layer "F.Fab")
		)
		(fp_line
			(start 0.299974 -0.150114)
			(end 0.299974 0.150114)
			(stroke
				(width 0.1)
				(type default)
			)
			(layer "F.Fab")
		)
		(pad "1" smd rect
			(at -0.2667 0 270)
			(size 0.3048 0.381)
			(layers "F.Cu" "F.Mask" "F.Paste")
			(net "P5E_CPU0_P0_TX_C_DN<10>")
		)
		(pad "2" smd rect
			(at 0.2667 0 270)
			(size 0.3048 0.381)
			(layers "F.Cu" "F.Mask" "F.Paste")
			(net "P5E_CPU0_P0_TX_DN<10>")
		)
	)
	(footprint ""
		(layer "F.Cu")
		(at 193.954908 -153.774902)
		(property "Reference" "H126"
			(at 6.2738 -0.68453 0)
			(unlocked yes)
			(layer "F.SilkS")
			(effects
				(font
					(size 0.7874 0.5842)
					(thickness 0.1524)
				)
				(justify left)
			)
		)
		(property "Value" ""
			(at 0 0 0)
			(layer "F.Fab")
			(effects
				(font
					(size 1.27 1.27)
				)
			)
		)
		(duplicate_pad_numbers_are_jumpers no)
		(fp_circle
			(center 0 0)
			(end 5.8166 0)
			(stroke
				(width 0.1524)
				(type default)
			)
			(fill no)
			(layer "F.SilkS")
		)
		(fp_circle
			(center 0 0)
			(end 5.8166 0)
			(stroke
				(width 0.1524)
				(type default)
			)
			(fill no)
			(layer "B.SilkS")
		)
		(fp_circle
			(center 0 0)
			(end 5.8166 0)
			(stroke
				(width 0.1)
				(type default)
			)
			(fill no)
			(layer "B.Fab")
		)
		(fp_circle
			(center 0 0)
			(end 5.8166 0)
			(stroke
				(width 0.1)
				(type default)
			)
			(fill no)
			(layer "F.Fab")
		)
		(pad "" np_thru_hole circle
			(at 0 0)
			(size 10.0076 10.0076)
			(drill 10.0076)
			(layers "*.Cu" "*.Mask")
			(clearance 0.381)
			(thermal_gap 0.381)
		)
	)
)
